# S9S_MB_2U (Grand Teton) — schematic netlist excerpt (pin names and nets, part order shuffled) for the footprints in the layout excerpt that follows; sources: Cadence DE-HDL packaged netlist, KiCad conversion of 03242023_DA0F0TMBIJ0_F0T_Motherboard_J_brd_V01_OCP.brd

R3349  Q_RES  1 1% CHIP  pkg 0603LF  page 217 : A = P3V3_AUX ; B = P3V3_AUX_FPGA_VCCIO5
R901  Q_RES  33.2 1% CHIP  pkg 0402LF  page 114 : A = PWRGD_CHE_CPU1_DIMM1 ; B = PWRGD_FAIL_CPU1_EF

(kicad_pcb
	(version 20260206)
	(generator "pcbnew")
	(generator_version "10.0")
	(general
		(thickness 1.6)
		(legacy_teardrops no)
	)
	(paper "A4")
	(title_block
		(title "03242023_DA0F0TMBIJ0_F0T_Motherboard_J_brd_V01_OCP.brd")
		(comment 1 "Grand Teton / footprints 5376-5377 of 6105")
	)
	(layers
		(0 "F.Cu" signal "TOP")
		(4 "In1.Cu" signal "GND")
		(6 "In2.Cu" signal "IN1")
		(8 "In3.Cu" signal "GND1")
		(10 "In4.Cu" signal "IN2")
		(12 "In5.Cu" signal "GND2")
		(14 "In6.Cu" signal "IN3")
		(16 "In7.Cu" signal "GND3")
		(18 "In8.Cu" signal "VCC")
		(20 "In9.Cu" signal "VCC1")
		(22 "In10.Cu" signal "GND4")
		(24 "In11.Cu" signal "IN4")
		(26 "In12.Cu" signal "GND5")
		(28 "In13.Cu" signal "IN5")
		(30 "In14.Cu" signal "GND6")
		(32 "In15.Cu" signal "IN6")
		(34 "In16.Cu" signal "GND7")
		(2 "B.Cu" signal "BOTTOM")
		(9 "F.Adhes" user "F.Adhesive")
		(11 "B.Adhes" user "B.Adhesive")
		(13 "F.Paste" user "Package Geometry/Pastemask Top")
		(15 "B.Paste" user "Package Geometry/Pastemask Bottom")
		(5 "F.SilkS" user "Ref Des/Silkscreen Top")
		(7 "B.SilkS" user "Ref Des/Silkscreen Bottom")
		(1 "F.Mask" user "Board Geometry/Soldermask Top")
		(3 "B.Mask" user "Board Geometry/Soldermask Bottom")
		(17 "Dwgs.User" user "User.Drawings")
		(19 "Cmts.User" user "User.Comments")
		(21 "Eco1.User" user "User.Eco1")
		(23 "Eco2.User" user "User.Eco2")
		(25 "Edge.Cuts" user "Board Geometry/Outline")
		(27 "Margin" user)
		(31 "F.CrtYd" user "Package Geometry/Place Bound Top")
		(29 "B.CrtYd" user "Package Geometry/Place Bound Bottom")
		(35 "F.Fab" user "Ref Des/Assembly Top")
		(33 "B.Fab" user "Ref Des/Assembly Bottom")
	)
	(footprint ""
		(layer "B.Cu")
		(at 167.078152 -318.23533)
		(property "Reference" "R901"
			(at 0 0 0)
			(layer "B.SilkS")
			(hide yes)
			(effects
				(font
					(size 1.27 1.27)
				)
				(justify mirror)
			)
		)
		(property "Value" ""
			(at 0 0 0)
			(layer "B.Fab")
			(effects
				(font
					(size 1.27 1.27)
				)
				(justify mirror)
			)
		)
		(duplicate_pad_numbers_are_jumpers no)
		(fp_line
			(start -0.7874 -0.4064)
			(end -0.7874 0.4064)
			(stroke
				(width 0.1524)
				(type default)
			)
			(layer "B.SilkS")
		)
		(fp_line
			(start -0.7874 0.4064)
			(end 0.7874 0.4064)
			(stroke
				(width 0.1524)
				(type default)
			)
			(layer "B.SilkS")
		)
		(fp_line
			(start 0.7874 -0.4064)
			(end -0.7874 -0.4064)
			(stroke
				(width 0.1524)
				(type default)
			)
			(layer "B.SilkS")
		)
		(fp_line
			(start 0.7874 0.4064)
			(end 0.7874 -0.4064)
			(stroke
				(width 0.1524)
				(type default)
			)
			(layer "B.SilkS")
		)
		(fp_line
			(start -0.67945 -0.3048)
			(end -0.67945 0.3048)
			(stroke
				(width 0.1)
				(type default)
			)
			(layer "B.Fab")
		)
		(fp_line
			(start -0.67945 0.3048)
			(end -0.120396 0.3048)
			(stroke
				(width 0.1)
				(type default)
			)
			(layer "B.Fab")
		)
		(fp_line
			(start -0.12065 -0.3048)
			(end -0.67945 -0.3048)
			(stroke
				(width 0.1)
				(type default)
			)
			(layer "B.Fab")
		)
		(fp_line
			(start -0.12065 -0.2794)
			(end -0.12065 -0.3048)
			(stroke
				(width 0.1)
				(type default)
			)
			(layer "B.Fab")
		)
		(fp_line
			(start -0.120396 0.2794)
			(end 0.12065 0.2794)
			(stroke
				(width 0.1)
				(type default)
			)
			(layer "B.Fab")
		)
		(fp_line
			(start -0.120396 0.3048)
			(end -0.120396 0.2794)
			(stroke
				(width 0.1)
				(type default)
			)
			(layer "B.Fab")
		)
		(fp_line
			(start 0.12065 -0.305054)
			(end 0.12065 -0.2794)
			(stroke
				(width 0.1)
				(type default)
			)
			(layer "B.Fab")
		)
		(fp_line
			(start 0.12065 -0.2794)
			(end -0.12065 -0.2794)
			(stroke
				(width 0.1)
				(type default)
			)
			(layer "B.Fab")
		)
		(fp_line
			(start 0.12065 0.2794)
			(end 0.12065 0.3048)
			(stroke
				(width 0.1)
				(type default)
			)
			(layer "B.Fab")
		)
		(fp_line
			(start 0.12065 0.3048)
			(end 0.67945 0.3048)
			(stroke
				(width 0.1)
				(type default)
			)
			(layer "B.Fab")
		)
		(fp_line
			(start 0.67945 -0.305054)
			(end 0.12065 -0.305054)
			(stroke
				(width 0.1)
				(type default)
			)
			(layer "B.Fab")
		)
		(fp_line
			(start 0.67945 0.3048)
			(end 0.67945 -0.305054)
			(stroke
				(width 0.1)
				(type default)
			)
			(layer "B.Fab")
		)
		(pad "1" smd circle
			(at 0.40005 0 180)
			(size 0 0)
			(layers "B.Cu" "B.Mask" "B.Paste")
			(net "PWRGD_CHE_CPU1_DIMM1")
		)
		(pad "2" smd circle
			(at -0.40005 0 180)
			(size 0 0)
			(layers "B.Cu" "B.Mask" "B.Paste")
			(net "PWRGD_FAIL_CPU1_EF")
		)
	)
	(footprint ""
		(layer "B.Cu")
		(at 173.04893 -101.564948 180)
		(property "Reference" "R3349"
			(at 0 0 0)
			(layer "B.SilkS")
			(hide yes)
			(effects
				(font
					(size 1.27 1.27)
				)
				(justify mirror)
			)
		)
		(property "Value" ""
			(at 0 0 0)
			(layer "B.Fab")
			(effects
				(font
					(size 1.27 1.27)
				)
				(justify mirror)
			)
		)
		(duplicate_pad_numbers_are_jumpers no)
		(fp_line
			(start 1.2954 0.5842)
			(end 1.2954 -0.5842)
			(stroke
				(width 0.1524)
				(type default)
			)
			(layer "B.SilkS")
		)
		(fp_line
			(start 1.2954 -0.5842)
			(end -1.2954 -0.5842)
			(stroke
				(width 0.1524)
				(type default)
			)
			(layer "B.SilkS")
		)
		(fp_line
			(start -1.2954 0.5842)
			(end 1.2954 0.5842)
			(stroke
				(width 0.1524)
				(type default)
			)
			(layer "B.SilkS")
		)
		(fp_line
			(start -1.2954 -0.5842)
			(end -1.2954 0.5842)
			(stroke
				(width 0.1524)
				(type default)
			)
			(layer "B.SilkS")
		)
		(fp_line
			(start 1.1938 0.4064)
			(end 1.1938 -0.406654)
			(stroke
				(width 0.1)
				(type default)
			)
			(layer "B.Fab")
		)
		(fp_line
			(start 1.1938 -0.406654)
			(end 0.8636 -0.406654)
			(stroke
				(width 0.1)
				(type default)
			)
			(layer "B.Fab")
		)
		(fp_line
			(start 0.8636 0.4572)
			(end 0.8636 0.4318)
			(stroke
				(width 0.1)
				(type default)
			)
			(layer "B.Fab")
		)
		(fp_line
			(start 0.8636 0.4318)
			(end 0.8636 0.4064)
			(stroke
				(width 0.1)
				(type default)
			)
			(layer "B.Fab")
		)
		(fp_line
			(start 0.8636 0.4064)
			(end 1.1938 0.4064)
			(stroke
				(width 0.1)
				(type default)
			)
			(layer "B.Fab")
		)
		(fp_line
			(start 0.8636 -0.406654)
			(end 0.8636 -0.4572)
			(stroke
				(width 0.1)
				(type default)
			)
			(layer "B.Fab")
		)
		(fp_line
			(start 0.8636 -0.4572)
			(end -0.8636 -0.4572)
			(stroke
				(width 0.1)
				(type default)
			)
			(layer "B.Fab")
		)
		(fp_line
			(start -0.8636 0.4572)
			(end 0.8636 0.4572)
			(stroke
				(width 0.1)
				(type default)
			)
			(layer "B.Fab")
		)
		(fp_line
			(start -0.8636 0.4064)
			(end -0.8636 0.4572)
			(stroke
				(width 0.1)
				(type default)
			)
			(layer "B.Fab")
		)
		(fp_line
			(start -0.8636 -0.406654)
			(end -1.1938 -0.406654)
			(stroke
				(width 0.1)
				(type default)
			)
			(layer "B.Fab")
		)
		(fp_line
			(start -0.8636 -0.4572)
			(end -0.8636 -0.406654)
			(stroke
				(width 0.1)
				(type default)
			)
			(layer "B.Fab")
		)
		(fp_line
			(start -1.1938 0.4064)
			(end -0.8636 0.4064)
			(stroke
				(width 0.1)
				(type default)
			)
			(layer "B.Fab")
		)
		(fp_line
			(start -1.1938 -0.406654)
			(end -1.1938 0.4064)
			(stroke
				(width 0.1)
				(type default)
			)
			(layer "B.Fab")
		)
		(pad "1" smd rect
			(at 0.7366 0 90)
			(size 0.7112 0.8128)
			(layers "B.Cu" "B.Mask" "B.Paste")
			(net "P3V3_AUX")
		)
		(pad "2" smd rect
			(at -0.7366 0 90)
			(size 0.7112 0.8128)
			(layers "B.Cu" "B.Mask" "B.Paste")
			(net "P3V3_AUX_FPGA_VCCIO5")
		)
	)
)
